# S9S_MB_2U (Grand Teton) — schematic netlist excerpt (pin names and nets, part order shuffled) for the footprints in the layout excerpt that follows; sources: Cadence DE-HDL packaged netlist, KiCad conversion of 03242023_DA0F0TMBIJ0_F0T_Motherboard_J_brd_V01_OCP.brd

R2828  Q_RES  100K 1% CHIP  pkg 0402LF  page 148 : A = P3V3_AUX ; B = RST_BMC_FROM_SWB_N
R2574  Q_RES  0 5% CHIP  pkg 0402LF  page 292 : A = IRQ_PVCCFA_CPU1_VRHOT_N ; B = IRQ_PVCCFA_CPU1_VRHOT_R_N

(kicad_pcb
	(version 20260206)
	(generator "pcbnew")
	(generator_version "10.0")
	(general
		(thickness 1.6)
		(legacy_teardrops no)
	)
	(paper "A4")
	(title_block
		(title "03242023_DA0F0TMBIJ0_F0T_Motherboard_J_brd_V01_OCP.brd")
		(comment 1 "Grand Teton / footprints 4037-4038 of 6105")
	)
	(layers
		(0 "F.Cu" signal "TOP")
		(4 "In1.Cu" signal "GND")
		(6 "In2.Cu" signal "IN1")
		(8 "In3.Cu" signal "GND1")
		(10 "In4.Cu" signal "IN2")
		(12 "In5.Cu" signal "GND2")
		(14 "In6.Cu" signal "IN3")
		(16 "In7.Cu" signal "GND3")
		(18 "In8.Cu" signal "VCC")
		(20 "In9.Cu" signal "VCC1")
		(22 "In10.Cu" signal "GND4")
		(24 "In11.Cu" signal "IN4")
		(26 "In12.Cu" signal "GND5")
		(28 "In13.Cu" signal "IN5")
		(30 "In14.Cu" signal "GND6")
		(32 "In15.Cu" signal "IN6")
		(34 "In16.Cu" signal "GND7")
		(2 "B.Cu" signal "BOTTOM")
		(9 "F.Adhes" user "F.Adhesive")
		(11 "B.Adhes" user "B.Adhesive")
		(13 "F.Paste" user "Package Geometry/Pastemask Top")
		(15 "B.Paste" user "Package Geometry/Pastemask Bottom")
		(5 "F.SilkS" user "Ref Des/Silkscreen Top")
		(7 "B.SilkS" user "Ref Des/Silkscreen Bottom")
		(1 "F.Mask" user "Board Geometry/Soldermask Top")
		(3 "B.Mask" user "Board Geometry/Soldermask Bottom")
		(17 "Dwgs.User" user "User.Drawings")
		(19 "Cmts.User" user "User.Comments")
		(21 "Eco1.User" user "User.Eco1")
		(23 "Eco2.User" user "User.Eco2")
		(25 "Edge.Cuts" user "Board Geometry/Outline")
		(27 "Margin" user)
		(31 "F.CrtYd" user "Package Geometry/Place Bound Top")
		(29 "B.CrtYd" user "Package Geometry/Place Bound Bottom")
		(35 "F.Fab" user "Ref Des/Assembly Top")
		(33 "B.Fab" user "Ref Des/Assembly Bottom")
	)
	(footprint ""
		(layer "F.Cu")
		(at 36.947348 -128.659382)
		(property "Reference" "R2574"
			(at 0 0 0)
			(layer "F.SilkS")
			(hide yes)
			(effects
				(font
					(size 1.27 1.27)
				)
			)
		)
		(property "Value" ""
			(at 0 0 0)
			(layer "F.Fab")
			(effects
				(font
					(size 1.27 1.27)
				)
			)
		)
		(duplicate_pad_numbers_are_jumpers no)
		(fp_line
			(start -0.7874 -0.4064)
			(end 0.7874 -0.4064)
			(stroke
				(width 0.1524)
				(type default)
			)
			(layer "F.SilkS")
		)
		(fp_line
			(start -0.7874 0.4064)
			(end -0.7874 -0.4064)
			(stroke
				(width 0.1524)
				(type default)
			)
			(layer "F.SilkS")
		)
		(fp_line
			(start 0.7874 -0.4064)
			(end 0.7874 0.4064)
			(stroke
				(width 0.1524)
				(type default)
			)
			(layer "F.SilkS")
		)
		(fp_line
			(start 0.7874 0.4064)
			(end -0.7874 0.4064)
			(stroke
				(width 0.1524)
				(type default)
			)
			(layer "F.SilkS")
		)
		(fp_line
			(start -0.67945 -0.305054)
			(end -0.12065 -0.305054)
			(stroke
				(width 0.1)
				(type default)
			)
			(layer "F.Fab")
		)
		(fp_line
			(start -0.67945 0.3048)
			(end -0.67945 -0.305054)
			(stroke
				(width 0.1)
				(type default)
			)
			(layer "F.Fab")
		)
		(fp_line
			(start -0.12065 -0.305054)
			(end -0.12065 -0.2794)
			(stroke
				(width 0.1)
				(type default)
			)
			(layer "F.Fab")
		)
		(fp_line
			(start -0.12065 -0.2794)
			(end 0.12065 -0.2794)
			(stroke
				(width 0.1)
				(type default)
			)
			(layer "F.Fab")
		)
		(fp_line
			(start -0.12065 0.2794)
			(end -0.12065 0.3048)
			(stroke
				(width 0.1)
				(type default)
			)
			(layer "F.Fab")
		)
		(fp_line
			(start -0.12065 0.3048)
			(end -0.67945 0.3048)
			(stroke
				(width 0.1)
				(type default)
			)
			(layer "F.Fab")
		)
		(fp_line
			(start 0.120396 0.2794)
			(end -0.12065 0.2794)
			(stroke
				(width 0.1)
				(type default)
			)
			(layer "F.Fab")
		)
		(fp_line
			(start 0.120396 0.3048)
			(end 0.120396 0.2794)
			(stroke
				(width 0.1)
				(type default)
			)
			(layer "F.Fab")
		)
		(fp_line
			(start 0.12065 -0.3048)
			(end 0.67945 -0.3048)
			(stroke
				(width 0.1)
				(type default)
			)
			(layer "F.Fab")
		)
		(fp_line
			(start 0.12065 -0.2794)
			(end 0.12065 -0.3048)
			(stroke
				(width 0.1)
				(type default)
			)
			(layer "F.Fab")
		)
		(fp_line
			(start 0.67945 -0.3048)
			(end 0.67945 0.3048)
			(stroke
				(width 0.1)
				(type default)
			)
			(layer "F.Fab")
		)
		(fp_line
			(start 0.67945 0.3048)
			(end 0.120396 0.3048)
			(stroke
				(width 0.1)
				(type default)
			)
			(layer "F.Fab")
		)
		(pad "1" smd circle
			(at -0.40005 0)
			(size 0 0)
			(layers "F.Cu" "F.Mask" "F.Paste")
			(net "IRQ_PVCCFA_CPU1_VRHOT_N")
		)
		(pad "2" smd circle
			(at 0.40005 0)
			(size 0 0)
			(layers "F.Cu" "F.Mask" "F.Paste")
			(net "IRQ_PVCCFA_CPU1_VRHOT_R_N")
		)
	)
	(footprint ""
		(layer "F.Cu")
		(at 424.204892 -381.345948)
		(property "Reference" "R2828"
			(at 0 0 0)
			(layer "F.SilkS")
			(hide yes)
			(effects
				(font
					(size 1.27 1.27)
				)
			)
		)
		(property "Value" ""
			(at 0 0 0)
			(layer "F.Fab")
			(effects
				(font
					(size 1.27 1.27)
				)
			)
		)
		(duplicate_pad_numbers_are_jumpers no)
		(fp_line
			(start -0.7874 -0.4064)
			(end 0.7874 -0.4064)
			(stroke
				(width 0.1524)
				(type default)
			)
			(layer "F.SilkS")
		)
		(fp_line
			(start -0.7874 0.4064)
			(end -0.7874 -0.4064)
			(stroke
				(width 0.1524)
				(type default)
			)
			(layer "F.SilkS")
		)
		(fp_line
			(start 0.7874 -0.4064)
			(end 0.7874 0.4064)
			(stroke
				(width 0.1524)
				(type default)
			)
			(layer "F.SilkS")
		)
		(fp_line
			(start 0.7874 0.4064)
			(end -0.7874 0.4064)
			(stroke
				(width 0.1524)
				(type default)
			)
			(layer "F.SilkS")
		)
		(fp_line
			(start -0.67945 -0.305054)
			(end -0.12065 -0.305054)
			(stroke
				(width 0.1)
				(type default)
			)
			(layer "F.Fab")
		)
		(fp_line
			(start -0.67945 0.3048)
			(end -0.67945 -0.305054)
			(stroke
				(width 0.1)
				(type default)
			)
			(layer "F.Fab")
		)
		(fp_line
			(start -0.12065 -0.305054)
			(end -0.12065 -0.2794)
			(stroke
				(width 0.1)
				(type default)
			)
			(layer "F.Fab")
		)
		(fp_line
			(start -0.12065 -0.2794)
			(end 0.12065 -0.2794)
			(stroke
				(width 0.1)
				(type default)
			)
			(layer "F.Fab")
		)
		(fp_line
			(start -0.12065 0.2794)
			(end -0.12065 0.3048)
			(stroke
				(width 0.1)
				(type default)
			)
			(layer "F.Fab")
		)
		(fp_line
			(start -0.12065 0.3048)
			(end -0.67945 0.3048)
			(stroke
				(width 0.1)
				(type default)
			)
			(layer "F.Fab")
		)
		(fp_line
			(start 0.120396 0.2794)
			(end -0.12065 0.2794)
			(stroke
				(width 0.1)
				(type default)
			)
			(layer "F.Fab")
		)
		(fp_line
			(start 0.120396 0.3048)
			(end 0.120396 0.2794)
			(stroke
				(width 0.1)
				(type default)
			)
			(layer "F.Fab")
		)
		(fp_line
			(start 0.12065 -0.3048)
			(end 0.67945 -0.3048)
			(stroke
				(width 0.1)
				(type default)
			)
			(layer "F.Fab")
		)
		(fp_line
			(start 0.12065 -0.2794)
			(end 0.12065 -0.3048)
			(stroke
				(width 0.1)
				(type default)
			)
			(layer "F.Fab")
		)
		(fp_line
			(start 0.67945 -0.3048)
			(end 0.67945 0.3048)
			(stroke
				(width 0.1)
				(type default)
			)
			(layer "F.Fab")
		)
		(fp_line
			(start 0.67945 0.3048)
			(end 0.120396 0.3048)
			(stroke
				(width 0.1)
				(type default)
			)
			(layer "F.Fab")
		)
		(pad "1" smd circle
			(at -0.40005 0)
			(size 0 0)
			(layers "F.Cu" "F.Mask" "F.Paste")
			(net "P3V3_AUX")
		)
		(pad "2" smd circle
			(at 0.40005 0)
			(size 0 0)
			(layers "F.Cu" "F.Mask" "F.Paste")
			(net "RST_BMC_FROM_SWB_N")
		)
	)
)
